(kicad_pcb
	(version 20260206)
	(generator "pcbnew")
	(generator_version "10.0")
	(general
		(thickness 1.6)
		(legacy_teardrops no)
	)
	(paper "A4")
	(title_block
		(title "Bryce Canyon_F.DPB_16315-1-OCP.brd")
		(comment 1 "Bryce Canyon / footprints 1552-1557 of 2223")
	)
	(layers
		(0 "F.Cu" signal "TOP")
		(4 "In1.Cu" signal "L2GND")
		(6 "In2.Cu" signal "L3")
		(8 "In3.Cu" signal "L4GND")
		(10 "In4.Cu" signal "L5")
		(12 "In5.Cu" signal "L6VCC")
		(14 "In6.Cu" signal "L7VCC")
		(16 "In7.Cu" signal "L8")
		(18 "In8.Cu" signal "L9GND")
		(20 "In9.Cu" signal "L10")
		(22 "In10.Cu" signal "L11GND")
		(2 "B.Cu" signal "BOTTOM")
		(9 "F.Adhes" user "F.Adhesive")
		(11 "B.Adhes" user "B.Adhesive")
		(13 "F.Paste" user "Package Geometry/Pastemask Top")
		(15 "B.Paste" user "Package Geometry/Pastemask Bottom")
		(5 "F.SilkS" user "Ref Des/Silkscreen Top")
		(7 "B.SilkS" user "Ref Des/Silkscreen Bottom")
		(1 "F.Mask" user "Board Geometry/Soldermask Top")
		(3 "B.Mask" user "Board Geometry/Soldermask Bottom")
		(17 "Dwgs.User" user "User.Drawings")
		(19 "Cmts.User" user "User.Comments")
		(21 "Eco1.User" user "User.Eco1")
		(23 "Eco2.User" user "User.Eco2")
		(25 "Edge.Cuts" user "Board Geometry/Outline")
		(27 "Margin" user)
		(31 "F.CrtYd" user "Package Geometry/Place Bound Top")
		(29 "B.CrtYd" user "Package Geometry/Place Bound Bottom")
		(35 "F.Fab" user "Ref Des/Assembly Top")
		(33 "B.Fab" user "Ref Des/Assembly Bottom")
	)
	(footprint ""
		(layer "F.Cu")
		(at 38.608762 -181.44617 90)
		(property "Reference" "R147"
			(at 0 0 90)
			(layer "F.SilkS")
			(hide yes)
			(effects
				(font
					(size 1.27 1.27)
				)
			)
		)
		(property "Value" "4K7R2J-2-GP"
			(at 0.064008 -3.993896 90)
			(unlocked yes)
			(layer "F.Fab")
			(hide yes)
			(effects
				(font
					(size 1.016 1.016)
					(thickness 0.1524)
				)
			)
		)
		(property "Device Type" "R402H16"
			(at 0.064008 -5.517896 90)
			(unlocked yes)
			(layer "F.Fab")
			(hide yes)
			(effects
				(font
					(size 1.016 1.016)
					(thickness 0.1524)
				)
			)
		)
		(duplicate_pad_numbers_are_jumpers no)
		(fp_line
			(start 0.508 -0.9398)
			(end -0.508 -0.9398)
			(stroke
				(width 0.1524)
				(type default)
			)
			(layer "F.SilkS")
		)
		(fp_line
			(start -0.508 -0.9398)
			(end -0.508 0.9398)
			(stroke
				(width 0.1524)
				(type default)
			)
			(layer "F.SilkS")
		)
		(fp_rect
			(start -0.508 0.9398)
			(end 0.508 -0.9398)
			(stroke
				(width 0)
				(type default)
			)
			(fill no)
			(layer "F.CrtYd")
		)
		(fp_rect
			(start -0.508 0.9398)
			(end 0.508 -0.9398)
			(stroke
				(width 0)
				(type default)
			)
			(fill no)
			(layer "F.Fab")
		)
		(pad "1" smd custom
			(at 0 -0.4445 90)
			(size 0.1397 0.1397)
			(layers "F.Cu" "F.Mask" "F.Paste")
			(net "DRIVE_A_1_ACT")
			(options
				(clearance outline)
				(anchor circle)
			)
			(primitives
				(gr_poly
					(pts
						(arc
							(start -0.1778 -0.2794)
							(mid -0.249642 -0.249642)
							(end -0.2794 -0.1778)
						)
						(arc
							(start -0.2794 0.1778)
							(mid -0.249642 0.249642)
							(end -0.1778 0.2794)
						)
						(arc
							(start 0.1778 0.2794)
							(mid 0.249642 0.249642)
							(end 0.2794 0.1778)
						)
						(arc
							(start 0.2794 -0.1778)
							(mid 0.249642 -0.249642)
							(end 0.1778 -0.2794)
						)
					)
					(width 0)
					(fill yes)
				)
			)
		)
		(pad "2" smd custom
			(at 0 0.4445 90)
			(size 0.1397 0.1397)
			(layers "F.Cu" "F.Mask" "F.Paste")
			(net "GND")
			(options
				(clearance outline)
				(anchor circle)
			)
			(primitives
				(gr_poly
					(pts
						(arc
							(start -0.1778 -0.2794)
							(mid -0.249642 -0.249642)
							(end -0.2794 -0.1778)
						)
						(arc
							(start -0.2794 0.1778)
							(mid -0.249642 0.249642)
							(end -0.1778 0.2794)
						)
						(arc
							(start 0.1778 0.2794)
							(mid 0.249642 0.249642)
							(end 0.2794 0.1778)
						)
						(arc
							(start 0.2794 -0.1778)
							(mid 0.249642 -0.249642)
							(end 0.1778 -0.2794)
						)
					)
					(width 0)
					(fill yes)
				)
			)
		)
	)
	(footprint ""
		(layer "F.Cu")
		(at 165.67531 -146.676618 90)
		(property "Reference" "R1067"
			(at 0 0 90)
			(layer "F.SilkS")
			(hide yes)
			(effects
				(font
					(size 1.27 1.27)
				)
			)
		)
		(property "Value" "10R5F-1-GP"
			(at 0 -8.9535 90)
			(unlocked yes)
			(layer "F.Fab")
			(hide yes)
			(effects
				(font
					(size 1.27 1.016)
					(thickness 0.1524)
				)
			)
		)
		(property "Device Type" "R805H24"
			(at 0 -10.6299 90)
			(unlocked yes)
			(layer "F.Fab")
			(hide yes)
			(effects
				(font
					(size 1.27 1.016)
					(thickness 0.1524)
				)
			)
		)
		(duplicate_pad_numbers_are_jumpers no)
		(fp_line
			(start 0.889 -1.7018)
			(end -0.889 -1.7018)
			(stroke
				(width 0.1524)
				(type default)
			)
			(layer "F.SilkS")
		)
		(fp_line
			(start 0.889 -1.7018)
			(end 0.889 -0.381)
			(stroke
				(width 0.1524)
				(type default)
			)
			(layer "F.SilkS")
		)
		(fp_line
			(start -0.889 -1.7018)
			(end -0.889 0.2794)
			(stroke
				(width 0.1524)
				(type default)
			)
			(layer "F.SilkS")
		)
		(fp_line
			(start -0.889 0.0762)
			(end -0.889 1.7018)
			(stroke
				(width 0.1524)
				(type default)
			)
			(layer "F.SilkS")
		)
		(fp_line
			(start 0.889 1.7018)
			(end 0.889 -0.508)
			(stroke
				(width 0.1524)
				(type default)
			)
			(layer "F.SilkS")
		)
		(fp_line
			(start -0.889 1.7018)
			(end 0.889 1.7018)
			(stroke
				(width 0.1524)
				(type default)
			)
			(layer "F.SilkS")
		)
		(fp_poly
			(pts
				(xy 0.9652 -1.778) (xy 0.9652 1.778) (xy -0.9652 1.778) (xy -0.9652 -1.778)
			)
			(stroke
				(width 0)
				(type default)
			)
			(fill no)
			(layer "F.CrtYd")
		)
		(fp_rect
			(start -0.9652 1.778)
			(end 0.9652 -1.778)
			(stroke
				(width 0)
				(type default)
			)
			(fill no)
			(layer "F.Fab")
		)
		(pad "1" smd rect
			(at 0 -0.9652 90)
			(size 1.397 1.143)
			(layers "F.Cu" "F.Mask" "F.Paste")
			(net "MB0_12V_CTRL_GATE1")
		)
		(pad "2" smd rect
			(at 0 0.9652 90)
			(size 1.397 1.143)
			(layers "F.Cu" "F.Mask" "F.Paste")
			(net "MB0_CM_GATE_R")
		)
	)
	(footprint ""
		(layer "F.Cu")
		(at 429.549052 -282.872942 -90)
		(property "Reference" "Q54"
			(at 0 0 270)
			(layer "F.SilkS")
			(hide yes)
			(effects
				(font
					(size 1.27 1.27)
				)
			)
		)
		(property "Value" "AO4406AL-GP"
			(at -3.707384 -1.5367 270)
			(unlocked yes)
			(layer "F.Fab")
			(hide yes)
			(effects
				(font
					(size 1.016 1.016)
					(thickness 0.1524)
				)
			)
		)
		(property "Device Type" "SOIC8H69"
			(at -3.707384 -3.0607 270)
			(unlocked yes)
			(layer "F.Fab")
			(hide yes)
			(effects
				(font
					(size 1.016 1.016)
					(thickness 0.1524)
				)
			)
		)
		(duplicate_pad_numbers_are_jumpers no)
		(fp_line
			(start -2.6289 3.4417)
			(end -2.6289 1.4732)
			(stroke
				(width 0.381)
				(type default)
			)
			(layer "F.SilkS")
		)
		(fp_line
			(start -2.7432 1.4224)
			(end -2.6416 1.4224)
			(stroke
				(width 0.1524)
				(type default)
			)
			(layer "F.SilkS")
		)
		(fp_line
			(start -2.7432 1.4224)
			(end 2.1336 1.4224)
			(stroke
				(width 0.1524)
				(type default)
			)
			(layer "F.SilkS")
		)
		(fp_line
			(start 2.1336 1.4224)
			(end 2.1336 -1.4224)
			(stroke
				(width 0.1524)
				(type default)
			)
			(layer "F.SilkS")
		)
		(fp_line
			(start -2.1844 -0.0508)
			(end -2.7178 0.508)
			(stroke
				(width 0.1524)
				(type default)
			)
			(layer "F.SilkS")
		)
		(fp_line
			(start -2.7178 -0.508)
			(end -2.1844 -0.0508)
			(stroke
				(width 0.1524)
				(type default)
			)
			(layer "F.SilkS")
		)
		(fp_line
			(start -2.7432 -1.4224)
			(end -2.7432 1.4224)
			(stroke
				(width 0.1524)
				(type default)
			)
			(layer "F.SilkS")
		)
		(fp_line
			(start 2.1336 -1.4224)
			(end -2.7432 -1.4224)
			(stroke
				(width 0.1524)
				(type default)
			)
			(layer "F.SilkS")
		)
		(fp_poly
			(pts
				(xy -2.2098 -1.4224) (xy -2.2098 1.4224) (xy 2.2098 1.4224) (xy 2.2098 -1.4224)
			)
			(stroke
				(width 0)
				(type default)
			)
			(fill yes)
			(layer "F.SilkS")
		)
		(fp_rect
			(start -2.450084 2.999994)
			(end 2.450084 -2.999994)
			(stroke
				(width 0)
				(type default)
			)
			(fill no)
			(layer "F.CrtYd")
		)
		(fp_poly
			(pts
				(xy -2.8194 3.6322) (xy -2.8194 -3.6322) (xy 2.8194 -3.6322) (xy 2.8194 1.18364) (xy 2.450084 1.18364)
				(xy 2.450084 -2.999994) (xy -2.450084 -2.999994) (xy -2.450084 2.999994) (xy 2.450084 2.999994)
				(xy 2.450084 1.18618) (xy 2.8194 1.18618) (xy 2.8194 3.6322)
			)
			(stroke
				(width 0)
				(type default)
			)
			(fill no)
			(layer "F.CrtYd")
		)
		(fp_rect
			(start -2.8194 3.6322)
			(end 2.8194 -3.6322)
			(stroke
				(width 0)
				(type default)
			)
			(fill no)
			(layer "F.Fab")
		)
		(pad "1" smd rect
			(at -1.905 2.54 270)
			(size 0.635 1.651)
			(layers "F.Cu" "F.Mask" "F.Paste")
			(net "P5V_HDD9")
		)
		(pad "2" smd rect
			(at -0.635 2.54 270)
			(size 0.635 1.651)
			(layers "F.Cu" "F.Mask" "F.Paste")
			(net "P5V_HDD9")
		)
		(pad "3" smd rect
			(at 0.635 2.54 270)
			(size 0.635 1.651)
			(layers "F.Cu" "F.Mask" "F.Paste")
			(net "P5V_HDD9")
		)
		(pad "4" smd rect
			(at 1.905 2.54 270)
			(size 0.635 1.651)
			(layers "F.Cu" "F.Mask" "F.Paste")
			(net "SW_HDD_P9")
		)
		(pad "5" smd rect
			(at 1.905 -2.54 270)
			(size 0.635 1.651)
			(layers "F.Cu" "F.Mask" "F.Paste")
			(net "P5V_A_3")
		)
		(pad "6" smd rect
			(at 0.635 -2.54 270)
			(size 0.635 1.651)
			(layers "F.Cu" "F.Mask" "F.Paste")
			(net "P5V_A_3")
		)
		(pad "7" smd rect
			(at -0.635 -2.54 270)
			(size 0.635 1.651)
			(layers "F.Cu" "F.Mask" "F.Paste")
			(net "P5V_A_3")
		)
		(pad "8" smd rect
			(at -1.905 -2.54 270)
			(size 0.635 1.651)
			(layers "F.Cu" "F.Mask" "F.Paste")
			(net "P5V_A_3")
		)
	)
	(footprint ""
		(layer "F.Cu")
		(at 47.090838 -148.082254 -90)
		(property "Reference" "R1232"
			(at 0 0 270)
			(layer "F.SilkS")
			(hide yes)
			(effects
				(font
					(size 1.27 1.27)
				)
			)
		)
		(property "Value" "200KR2F-L-GP"
			(at 0.064008 -3.993896 270)
			(unlocked yes)
			(layer "F.Fab")
			(hide yes)
			(effects
				(font
					(size 1.016 1.016)
					(thickness 0.1524)
				)
			)
		)
		(property "Device Type" "R402H16"
			(at 0.064008 -5.517896 270)
			(unlocked yes)
			(layer "F.Fab")
			(hide yes)
			(effects
				(font
					(size 1.016 1.016)
					(thickness 0.1524)
				)
			)
		)
		(duplicate_pad_numbers_are_jumpers no)
		(fp_line
			(start -0.508 -0.9398)
			(end -0.508 0.9398)
			(stroke
				(width 0.1524)
				(type default)
			)
			(layer "F.SilkS")
		)
		(fp_line
			(start 0.508 -0.9398)
			(end -0.508 -0.9398)
			(stroke
				(width 0.1524)
				(type default)
			)
			(layer "F.SilkS")
		)
		(fp_rect
			(start -0.508 0.9398)
			(end 0.508 -0.9398)
			(stroke
				(width 0)
				(type default)
			)
			(fill no)
			(layer "F.CrtYd")
		)
		(fp_rect
			(start -0.508 0.9398)
			(end 0.508 -0.9398)
			(stroke
				(width 0)
				(type default)
			)
			(fill no)
			(layer "F.Fab")
		)
		(pad "1" smd custom
			(at 0 -0.4445 270)
			(size 0.1397 0.1397)
			(layers "F.Cu" "F.Mask" "F.Paste")
			(net "P5V_B_MODE")
			(options
				(clearance outline)
				(anchor circle)
			)
			(primitives
				(gr_poly
					(pts
						(arc
							(start -0.1778 -0.2794)
							(mid -0.249642 -0.249642)
							(end -0.2794 -0.1778)
						)
						(arc
							(start -0.2794 0.1778)
							(mid -0.249642 0.249642)
							(end -0.1778 0.2794)
						)
						(arc
							(start 0.1778 0.2794)
							(mid 0.249642 0.249642)
							(end 0.2794 0.1778)
						)
						(arc
							(start 0.2794 -0.1778)
							(mid 0.249642 -0.249642)
							(end 0.1778 -0.2794)
						)
					)
					(width 0)
					(fill yes)
				)
			)
		)
		(pad "2" smd custom
			(at 0 0.4445 270)
			(size 0.1397 0.1397)
			(layers "F.Cu" "F.Mask" "F.Paste")
			(net "P5V_A_2_PGOOD")
			(options
				(clearance outline)
				(anchor circle)
			)
			(primitives
				(gr_poly
					(pts
						(arc
							(start -0.1778 -0.2794)
							(mid -0.249642 -0.249642)
							(end -0.2794 -0.1778)
						)
						(arc
							(start -0.2794 0.1778)
							(mid -0.249642 0.249642)
							(end -0.1778 0.2794)
						)
						(arc
							(start 0.1778 0.2794)
							(mid 0.249642 0.249642)
							(end 0.2794 0.1778)
						)
						(arc
							(start 0.2794 -0.1778)
							(mid 0.249642 -0.249642)
							(end 0.1778 -0.2794)
						)
					)
					(width 0)
					(fill yes)
				)
			)
		)
	)
	(footprint ""
		(layer "F.Cu")
		(at 366.449102 -282.872942 -90)
		(property "Reference" "Q42"
			(at 0 0 270)
			(layer "F.SilkS")
			(hide yes)
			(effects
				(font
					(size 1.27 1.27)
				)
			)
		)
		(property "Value" "AO4406AL-GP"
			(at -3.707384 -1.5367 270)
			(unlocked yes)
			(layer "F.Fab")
			(hide yes)
			(effects
				(font
					(size 1.016 1.016)
					(thickness 0.1524)
				)
			)
		)
		(property "Device Type" "SOIC8H69"
			(at -3.707384 -3.0607 270)
			(unlocked yes)
			(layer "F.Fab")
			(hide yes)
			(effects
				(font
					(size 1.016 1.016)
					(thickness 0.1524)
				)
			)
		)
		(duplicate_pad_numbers_are_jumpers no)
		(fp_line
			(start -2.6289 3.4417)
			(end -2.6289 1.4732)
			(stroke
				(width 0.381)
				(type default)
			)
			(layer "F.SilkS")
		)
		(fp_line
			(start -2.7432 1.4224)
			(end -2.6416 1.4224)
			(stroke
				(width 0.1524)
				(type default)
			)
			(layer "F.SilkS")
		)
		(fp_line
			(start -2.7432 1.4224)
			(end 2.1336 1.4224)
			(stroke
				(width 0.1524)
				(type default)
			)
			(layer "F.SilkS")
		)
		(fp_line
			(start 2.1336 1.4224)
			(end 2.1336 -1.4224)
			(stroke
				(width 0.1524)
				(type default)
			)
			(layer "F.SilkS")
		)
		(fp_line
			(start -2.1844 -0.0508)
			(end -2.7178 0.508)
			(stroke
				(width 0.1524)
				(type default)
			)
			(layer "F.SilkS")
		)
		(fp_line
			(start -2.7178 -0.508)
			(end -2.1844 -0.0508)
			(stroke
				(width 0.1524)
				(type default)
			)
			(layer "F.SilkS")
		)
		(fp_line
			(start -2.7432 -1.4224)
			(end -2.7432 1.4224)
			(stroke
				(width 0.1524)
				(type default)
			)
			(layer "F.SilkS")
		)
		(fp_line
			(start 2.1336 -1.4224)
			(end -2.7432 -1.4224)
			(stroke
				(width 0.1524)
				(type default)
			)
			(layer "F.SilkS")
		)
		(fp_poly
			(pts
				(xy -2.2098 -1.4224) (xy -2.2098 1.4224) (xy 2.2098 1.4224) (xy 2.2098 -1.4224)
			)
			(stroke
				(width 0)
				(type default)
			)
			(fill yes)
			(layer "F.SilkS")
		)
		(fp_rect
			(start -2.450084 2.999994)
			(end 2.450084 -2.999994)
			(stroke
				(width 0)
				(type default)
			)
			(fill no)
			(layer "F.CrtYd")
		)
		(fp_poly
			(pts
				(xy -2.8194 3.6322) (xy -2.8194 -3.6322) (xy 2.8194 -3.6322) (xy 2.8194 1.18364) (xy 2.450084 1.18364)
				(xy 2.450084 -2.999994) (xy -2.450084 -2.999994) (xy -2.450084 2.999994) (xy 2.450084 2.999994)
				(xy 2.450084 1.18618) (xy 2.8194 1.18618) (xy 2.8194 3.6322)
			)
			(stroke
				(width 0)
				(type default)
			)
			(fill no)
			(layer "F.CrtYd")
		)
		(fp_rect
			(start -2.8194 3.6322)
			(end 2.8194 -3.6322)
			(stroke
				(width 0)
				(type default)
			)
			(fill no)
			(layer "F.Fab")
		)
		(pad "1" smd rect
			(at -1.905 2.54 270)
			(size 0.635 1.651)
			(layers "F.Cu" "F.Mask" "F.Paste")
			(net "P5V_HDD7")
		)
		(pad "2" smd rect
			(at -0.635 2.54 270)
			(size 0.635 1.651)
			(layers "F.Cu" "F.Mask" "F.Paste")
			(net "P5V_HDD7")
		)
		(pad "3" smd rect
			(at 0.635 2.54 270)
			(size 0.635 1.651)
			(layers "F.Cu" "F.Mask" "F.Paste")
			(net "P5V_HDD7")
		)
		(pad "4" smd rect
			(at 1.905 2.54 270)
			(size 0.635 1.651)
			(layers "F.Cu" "F.Mask" "F.Paste")
			(net "SW_HDD_P7")
		)
		(pad "5" smd rect
			(at 1.905 -2.54 270)
			(size 0.635 1.651)
			(layers "F.Cu" "F.Mask" "F.Paste")
			(net "P5V_A_3")
		)
		(pad "6" smd rect
			(at 0.635 -2.54 270)
			(size 0.635 1.651)
			(layers "F.Cu" "F.Mask" "F.Paste")
			(net "P5V_A_3")
		)
		(pad "7" smd rect
			(at -0.635 -2.54 270)
			(size 0.635 1.651)
			(layers "F.Cu" "F.Mask" "F.Paste")
			(net "P5V_A_3")
		)
		(pad "8" smd rect
			(at -1.905 -2.54 270)
			(size 0.635 1.651)
			(layers "F.Cu" "F.Mask" "F.Paste")
			(net "P5V_A_3")
		)
	)
	(footprint ""
		(layer "F.Cu")
		(at 67.347846 -292.169342 -90)
		(property "Reference" "R153"
			(at 0 0 270)
			(layer "F.SilkS")
			(hide yes)
			(effects
				(font
					(size 1.27 1.27)
				)
			)
		)
		(property "Value" "10KR2F-2-GP"
			(at 0.064008 -3.993896 270)
			(unlocked yes)
			(layer "F.Fab")
			(hide yes)
			(effects
				(font
					(size 1.016 1.016)
					(thickness 0.1524)
				)
			)
		)
		(property "Device Type" "R402H16"
			(at 0.064008 -5.517896 270)
			(unlocked yes)
			(layer "F.Fab")
			(hide yes)
			(effects
				(font
					(size 1.016 1.016)
					(thickness 0.1524)
				)
			)
		)
		(duplicate_pad_numbers_are_jumpers no)
		(fp_line
			(start -0.508 -0.9398)
			(end -0.508 0.9398)
			(stroke
				(width 0.1524)
				(type default)
			)
			(layer "F.SilkS")
		)
		(fp_line
			(start 0.508 -0.9398)
			(end -0.508 -0.9398)
			(stroke
				(width 0.1524)
				(type default)
			)
			(layer "F.SilkS")
		)
		(fp_rect
			(start -0.508 0.9398)
			(end 0.508 -0.9398)
			(stroke
				(width 0)
				(type default)
			)
			(fill no)
			(layer "F.CrtYd")
		)
		(fp_rect
			(start -0.508 0.9398)
			(end 0.508 -0.9398)
			(stroke
				(width 0)
				(type default)
			)
			(fill no)
			(layer "F.Fab")
		)
		(pad "1" smd custom
			(at 0 -0.4445 270)
			(size 0.1397 0.1397)
			(layers "F.Cu" "F.Mask" "F.Paste")
			(net "P3V3_STBY_A")
			(options
				(clearance outline)
				(anchor circle)
			)
			(primitives
				(gr_poly
					(pts
						(arc
							(start -0.1778 -0.2794)
							(mid -0.249642 -0.249642)
							(end -0.2794 -0.1778)
						)
						(arc
							(start -0.2794 0.1778)
							(mid -0.249642 0.249642)
							(end -0.1778 0.2794)
						)
						(arc
							(start 0.1778 0.2794)
							(mid 0.249642 0.249642)
							(end 0.2794 0.1778)
						)
						(arc
							(start 0.2794 -0.1778)
							(mid 0.249642 -0.249642)
							(end 0.1778 -0.2794)
						)
					)
					(width 0)
					(fill yes)
				)
			)
		)
		(pad "2" smd custom
			(at 0 0.4445 270)
			(size 0.1397 0.1397)
			(layers "F.Cu" "F.Mask" "F.Paste")
			(net "HDD_PRSNT_1")
			(options
				(clearance outline)
				(anchor circle)
			)
			(primitives
				(gr_poly
					(pts
						(arc
							(start -0.1778 -0.2794)
							(mid -0.249642 -0.249642)
							(end -0.2794 -0.1778)
						)
						(arc
							(start -0.2794 0.1778)
							(mid -0.249642 0.249642)
							(end -0.1778 0.2794)
						)
						(arc
							(start 0.1778 0.2794)
							(mid 0.249642 0.249642)
							(end 0.2794 0.1778)
						)
						(arc
							(start 0.2794 -0.1778)
							(mid 0.249642 -0.249642)
							(end 0.1778 -0.2794)
						)
					)
					(width 0)
					(fill yes)
				)
			)
		)
	)
)
